(kicad_pcb
	(version 20260206)
	(generator "pcbnew")
	(generator_version "10.0")
	(general
		(thickness 1.6)
		(legacy_teardrops no)
	)
	(paper "A4")
	(title_block
		(title "Bryce Canyon_IOM_M2_16342-2_OCP.brd")
		(comment 1 "Bryce Canyon / footprints 177-184 of 1146")
	)
	(layers
		(0 "F.Cu" signal "TOP")
		(4 "In1.Cu" signal "L2GND")
		(6 "In2.Cu" signal "L3")
		(8 "In3.Cu" signal "L4VCC")
		(10 "In4.Cu" signal "L5VCC")
		(12 "In5.Cu" signal "L6")
		(14 "In6.Cu" signal "L7GND")
		(2 "B.Cu" signal "BOTTOM")
		(9 "F.Adhes" user "F.Adhesive")
		(11 "B.Adhes" user "B.Adhesive")
		(13 "F.Paste" user "Package Geometry/Pastemask Top")
		(15 "B.Paste" user "Package Geometry/Pastemask Bottom")
		(5 "F.SilkS" user "Ref Des/Silkscreen Top")
		(7 "B.SilkS" user "Ref Des/Silkscreen Bottom")
		(1 "F.Mask" user "Board Geometry/Soldermask Top")
		(3 "B.Mask" user "Board Geometry/Soldermask Bottom")
		(17 "Dwgs.User" user "User.Drawings")
		(19 "Cmts.User" user "User.Comments")
		(21 "Eco1.User" user "User.Eco1")
		(23 "Eco2.User" user "User.Eco2")
		(25 "Edge.Cuts" user "Board Geometry/Outline")
		(27 "Margin" user)
		(31 "F.CrtYd" user "Package Geometry/Place Bound Top")
		(29 "B.CrtYd" user "Package Geometry/Place Bound Bottom")
		(35 "F.Fab" user "Ref Des/Assembly Top")
		(33 "B.Fab" user "Ref Des/Assembly Bottom")
	)
	(footprint ""
		(layer "F.Cu")
		(at 95.220282 -46.444662)
		(property "Reference" "R500"
			(at 0 0 0)
			(layer "F.SilkS")
			(hide yes)
			(effects
				(font
					(size 1.27 1.27)
				)
			)
		)
		(property "Value" "2K2R2J-2-GP"
			(at 0.064008 -3.993896 0)
			(unlocked yes)
			(layer "F.Fab")
			(hide yes)
			(effects
				(font
					(size 1.016 1.016)
					(thickness 0.1524)
				)
			)
		)
		(property "Device Type" "R402H16"
			(at 0.064008 -5.517896 0)
			(unlocked yes)
			(layer "F.Fab")
			(hide yes)
			(effects
				(font
					(size 1.016 1.016)
					(thickness 0.1524)
				)
			)
		)
		(duplicate_pad_numbers_are_jumpers no)
		(fp_line
			(start -0.508 -0.9398)
			(end -0.508 0.9398)
			(stroke
				(width 0.1524)
				(type default)
			)
			(layer "F.SilkS")
		)
		(fp_line
			(start 0.508 -0.9398)
			(end -0.508 -0.9398)
			(stroke
				(width 0.1524)
				(type default)
			)
			(layer "F.SilkS")
		)
		(fp_rect
			(start -0.508 0.9398)
			(end 0.508 -0.9398)
			(stroke
				(width 0)
				(type default)
			)
			(fill no)
			(layer "F.CrtYd")
		)
		(fp_rect
			(start -0.508 0.9398)
			(end 0.508 -0.9398)
			(stroke
				(width 0)
				(type default)
			)
			(fill no)
			(layer "F.Fab")
		)
		(pad "1" smd custom
			(at 0 -0.4445)
			(size 0.1397 0.1397)
			(layers "F.Cu" "F.Mask" "F.Paste")
			(net "P3V3_STBY")
			(options
				(clearance outline)
				(anchor circle)
			)
			(primitives
				(gr_poly
					(pts
						(arc
							(start -0.1778 -0.2794)
							(mid -0.249642 -0.249642)
							(end -0.2794 -0.1778)
						)
						(arc
							(start -0.2794 0.1778)
							(mid -0.249642 0.249642)
							(end -0.1778 0.2794)
						)
						(arc
							(start 0.1778 0.2794)
							(mid 0.249642 0.249642)
							(end 0.2794 0.1778)
						)
						(arc
							(start 0.2794 -0.1778)
							(mid 0.249642 -0.249642)
							(end 0.1778 -0.2794)
						)
					)
					(width 0)
					(fill yes)
				)
			)
		)
		(pad "2" smd custom
			(at 0 0.4445)
			(size 0.1397 0.1397)
			(layers "F.Cu" "F.Mask" "F.Paste")
			(net "PQ2_G")
			(options
				(clearance outline)
				(anchor circle)
			)
			(primitives
				(gr_poly
					(pts
						(arc
							(start -0.1778 -0.2794)
							(mid -0.249642 -0.249642)
							(end -0.2794 -0.1778)
						)
						(arc
							(start -0.2794 0.1778)
							(mid -0.249642 0.249642)
							(end -0.1778 0.2794)
						)
						(arc
							(start 0.1778 0.2794)
							(mid 0.249642 0.249642)
							(end 0.2794 0.1778)
						)
						(arc
							(start 0.2794 -0.1778)
							(mid 0.249642 -0.249642)
							(end 0.1778 -0.2794)
						)
					)
					(width 0)
					(fill yes)
				)
			)
		)
	)
	(footprint ""
		(layer "F.Cu")
		(at 60.375546 -182.561738 -90)
		(property "Reference" "R481"
			(at 0 0 270)
			(layer "F.SilkS")
			(hide yes)
			(effects
				(font
					(size 1.27 1.27)
				)
			)
		)
		(property "Value" "0R6J-3-GP"
			(at -0.0508 -4.8514 270)
			(unlocked yes)
			(layer "F.Fab")
			(hide yes)
			(effects
				(font
					(size 1.016 1.016)
					(thickness 0.1524)
				)
			)
		)
		(property "Device Type" "R1206H28"
			(at 0 -6.3754 270)
			(unlocked yes)
			(layer "F.Fab")
			(hide yes)
			(effects
				(font
					(size 1.016 1.016)
					(thickness 0.1524)
				)
			)
		)
		(duplicate_pad_numbers_are_jumpers no)
		(fp_line
			(start -1.016 2.2352)
			(end -1.016 -2.2352)
			(stroke
				(width 0.1524)
				(type default)
			)
			(layer "F.SilkS")
		)
		(fp_line
			(start 1.016 2.2352)
			(end -1.016 2.2352)
			(stroke
				(width 0.1524)
				(type default)
			)
			(layer "F.SilkS")
		)
		(fp_line
			(start -1.016 -2.2352)
			(end 1.016 -2.2352)
			(stroke
				(width 0.1524)
				(type default)
			)
			(layer "F.SilkS")
		)
		(fp_line
			(start 1.016 -2.2352)
			(end 1.016 2.2352)
			(stroke
				(width 0.1524)
				(type default)
			)
			(layer "F.SilkS")
		)
		(fp_rect
			(start -1.0922 2.3114)
			(end 1.0922 -2.3114)
			(stroke
				(width 0)
				(type default)
			)
			(fill no)
			(layer "F.CrtYd")
		)
		(fp_poly
			(pts
				(xy -1.0922 -2.3114) (xy 1.0922 -2.3114) (xy 1.0922 2.3114) (xy -1.0922 2.3114)
			)
			(stroke
				(width 0)
				(type default)
			)
			(fill no)
			(layer "F.Fab")
		)
		(pad "1" smd rect
			(at 0 -1.397 270)
			(size 1.651 1.27)
			(layers "F.Cu" "F.Mask" "F.Paste")
			(net "P3V3_STBY")
		)
		(pad "2" smd rect
			(at 0 1.397 270)
			(size 1.651 1.27)
			(layers "F.Cu" "F.Mask" "F.Paste")
			(net "P3V3_STBY_OUT")
		)
	)
	(footprint ""
		(layer "F.Cu")
		(at 93.7514 -150.369524 -90)
		(property "Reference" "TP5"
			(at 0 0 270)
			(layer "F.SilkS")
			(hide yes)
			(effects
				(font
					(size 1.27 1.27)
				)
			)
		)
		(property "Value" "TPAD28-2-GP"
			(at -0.0127 -1.6637 270)
			(unlocked yes)
			(layer "F.Fab")
			(hide yes)
			(effects
				(font
					(size 1.016 1.016)
					(thickness 0.1524)
				)
			)
		)
		(property "Device Type" "TPAD28"
			(at -0.0127 -3.1877 270)
			(unlocked yes)
			(layer "F.Fab")
			(hide yes)
			(effects
				(font
					(size 1.016 1.016)
					(thickness 0.1524)
				)
			)
		)
		(duplicate_pad_numbers_are_jumpers no)
		(fp_poly
			(pts
				(arc
					(start 0 -0.3556)
					(mid 0 0.3556)
					(end 0 -0.3556)
				)
			)
			(stroke
				(width 0)
				(type default)
			)
			(fill no)
			(layer "F.CrtYd")
		)
		(fp_poly
			(pts
				(arc
					(start 0 -0.6096)
					(mid 0 0.6096)
					(end 0 -0.6096)
				)
			)
			(stroke
				(width 0)
				(type default)
			)
			(fill no)
			(layer "F.Fab")
		)
		(pad "1" smd circle
			(at 0 0 270)
			(size 0.7112 0.7112)
			(layers "F.Cu" "F.Mask" "F.Paste")
			(net "CRFILT")
		)
	)
	(footprint ""
		(layer "F.Cu")
		(at 61.907674 -178.834796)
		(property "Reference" "C33"
			(at 0 0 0)
			(layer "F.SilkS")
			(hide yes)
			(effects
				(font
					(size 1.27 1.27)
				)
			)
		)
		(property "Value" "SCD1U16V2KX-3GP"
			(at 1.1811 -2.7051 0)
			(unlocked yes)
			(layer "F.Fab")
			(hide yes)
			(effects
				(font
					(size 1.016 1.016)
					(thickness 0.1524)
				)
			)
		)
		(property "Device Type" "C402H22"
			(at 1.1811 -4.2291 0)
			(unlocked yes)
			(layer "F.Fab")
			(hide yes)
			(effects
				(font
					(size 1.016 1.016)
					(thickness 0.1524)
				)
			)
		)
		(duplicate_pad_numbers_are_jumpers no)
		(fp_rect
			(start -0.4318 0.9525)
			(end 0.4318 -0.9525)
			(stroke
				(width 0)
				(type default)
			)
			(fill no)
			(layer "F.CrtYd")
		)
		(fp_rect
			(start -0.4318 0.9525)
			(end 0.4318 -0.9525)
			(stroke
				(width 0)
				(type default)
			)
			(fill no)
			(layer "F.Fab")
		)
		(pad "1" smd custom
			(at 0 -0.4445)
			(size 0.1524 0.1524)
			(layers "F.Cu" "F.Mask" "F.Paste")
			(net "P3V3_STBY")
			(options
				(clearance outline)
				(anchor circle)
			)
			(primitives
				(gr_poly
					(pts
						(arc
							(start 0.3048 -0.2032)
							(mid 0.275042 -0.275042)
							(end 0.2032 -0.3048)
						)
						(arc
							(start -0.2032 -0.3048)
							(mid -0.275042 -0.275042)
							(end -0.3048 -0.2032)
						)
						(arc
							(start -0.3048 0.2032)
							(mid -0.275042 0.275042)
							(end -0.2032 0.3048)
						)
						(arc
							(start 0.2032 0.3048)
							(mid 0.275042 0.275042)
							(end 0.3048 0.2032)
						)
					)
					(width 0)
					(fill yes)
				)
			)
		)
		(pad "2" smd custom
			(at 0 0.4445)
			(size 0.1524 0.1524)
			(layers "F.Cu" "F.Mask" "F.Paste")
			(net "GND")
			(options
				(clearance outline)
				(anchor circle)
			)
			(primitives
				(gr_poly
					(pts
						(arc
							(start 0.3048 -0.2032)
							(mid 0.275042 -0.275042)
							(end 0.2032 -0.3048)
						)
						(arc
							(start -0.2032 -0.3048)
							(mid -0.275042 -0.275042)
							(end -0.3048 -0.2032)
						)
						(arc
							(start -0.3048 0.2032)
							(mid -0.275042 0.275042)
							(end -0.2032 0.3048)
						)
						(arc
							(start 0.2032 0.3048)
							(mid 0.275042 0.275042)
							(end 0.3048 0.2032)
						)
					)
					(width 0)
					(fill yes)
				)
			)
		)
	)
	(footprint ""
		(layer "F.Cu")
		(at 128.94691 -8.745728 90)
		(property "Reference" "R709"
			(at 0 0 90)
			(layer "F.SilkS")
			(hide yes)
			(effects
				(font
					(size 1.27 1.27)
				)
			)
		)
		(property "Value" "0R5J-5-GP"
			(at 0 -8.953754 90)
			(unlocked yes)
			(layer "F.Fab")
			(hide yes)
			(effects
				(font
					(size 1.27 1.016)
					(thickness 0.1524)
				)
			)
		)
		(property "Device Type" "R805H24"
			(at 0 -10.629646 90)
			(unlocked yes)
			(layer "F.Fab")
			(hide yes)
			(effects
				(font
					(size 1.27 1.016)
					(thickness 0.1524)
				)
			)
		)
		(duplicate_pad_numbers_are_jumpers no)
		(fp_line
			(start 0.888746 -1.7018)
			(end -0.888746 -1.7018)
			(stroke
				(width 0.1524)
				(type default)
			)
			(layer "F.SilkS")
		)
		(fp_line
			(start 0.888746 -1.7018)
			(end 0.889 -0.381)
			(stroke
				(width 0.1524)
				(type default)
			)
			(layer "F.SilkS")
		)
		(fp_line
			(start -0.888746 -1.7018)
			(end -0.889 0.2794)
			(stroke
				(width 0.1524)
				(type default)
			)
			(layer "F.SilkS")
		)
		(fp_line
			(start -0.889 0.0762)
			(end -0.888746 1.7018)
			(stroke
				(width 0.1524)
				(type default)
			)
			(layer "F.SilkS")
		)
		(fp_line
			(start 0.888746 1.7018)
			(end 0.889 -0.508)
			(stroke
				(width 0.1524)
				(type default)
			)
			(layer "F.SilkS")
		)
		(fp_line
			(start -0.888746 1.7018)
			(end 0.888746 1.7018)
			(stroke
				(width 0.1524)
				(type default)
			)
			(layer "F.SilkS")
		)
		(fp_poly
			(pts
				(xy 0.9652 -1.778) (xy 0.9652 1.778) (xy -0.9652 1.778) (xy -0.9652 -1.778)
			)
			(stroke
				(width 0)
				(type default)
			)
			(fill no)
			(layer "F.CrtYd")
		)
		(fp_rect
			(start -0.9652 1.778)
			(end 0.9652 -1.778)
			(stroke
				(width 0)
				(type default)
			)
			(fill no)
			(layer "F.Fab")
		)
		(pad "1" smd rect
			(at 0 -0.9652 90)
			(size 1.397 1.143)
			(layers "F.Cu" "F.Mask" "F.Paste")
			(net "MB0_CM_GATE_2")
		)
		(pad "2" smd rect
			(at 0 0.9652 90)
			(size 1.397 1.143)
			(layers "F.Cu" "F.Mask" "F.Paste")
			(net "MB0_CM_GATE_R")
		)
	)
	(footprint ""
		(layer "F.Cu")
		(at 110.71479 -9.666478 -90)
		(property "Reference" "R454"
			(at 0 0 270)
			(layer "F.SilkS")
			(hide yes)
			(effects
				(font
					(size 1.27 1.27)
				)
			)
		)
		(property "Value" "66K5R2F-GP"
			(at 0.064008 -3.993896 270)
			(unlocked yes)
			(layer "F.Fab")
			(hide yes)
			(effects
				(font
					(size 1.016 1.016)
					(thickness 0.1524)
				)
			)
		)
		(property "Device Type" "R402H16"
			(at 0.064008 -5.517896 270)
			(unlocked yes)
			(layer "F.Fab")
			(hide yes)
			(effects
				(font
					(size 1.016 1.016)
					(thickness 0.1524)
				)
			)
		)
		(duplicate_pad_numbers_are_jumpers no)
		(fp_line
			(start -0.508 -0.9398)
			(end -0.508 0.9398)
			(stroke
				(width 0.1524)
				(type default)
			)
			(layer "F.SilkS")
		)
		(fp_line
			(start 0.508 -0.9398)
			(end -0.508 -0.9398)
			(stroke
				(width 0.1524)
				(type default)
			)
			(layer "F.SilkS")
		)
		(fp_rect
			(start -0.508 0.9398)
			(end 0.508 -0.9398)
			(stroke
				(width 0)
				(type default)
			)
			(fill no)
			(layer "F.CrtYd")
		)
		(fp_rect
			(start -0.508 0.9398)
			(end 0.508 -0.9398)
			(stroke
				(width 0)
				(type default)
			)
			(fill no)
			(layer "F.Fab")
		)
		(pad "1" smd custom
			(at 0 -0.4445 270)
			(size 0.1397 0.1397)
			(layers "F.Cu" "F.Mask" "F.Paste")
			(net "MB0_ISET_R")
			(options
				(clearance outline)
				(anchor circle)
			)
			(primitives
				(gr_poly
					(pts
						(arc
							(start -0.1778 -0.2794)
							(mid -0.249642 -0.249642)
							(end -0.2794 -0.1778)
						)
						(arc
							(start -0.2794 0.1778)
							(mid -0.249642 0.249642)
							(end -0.1778 0.2794)
						)
						(arc
							(start 0.1778 0.2794)
							(mid 0.249642 0.249642)
							(end 0.2794 0.1778)
						)
						(arc
							(start 0.2794 -0.1778)
							(mid 0.249642 -0.249642)
							(end 0.1778 -0.2794)
						)
					)
					(width 0)
					(fill yes)
				)
			)
		)
		(pad "2" smd custom
			(at 0 0.4445 270)
			(size 0.1397 0.1397)
			(layers "F.Cu" "F.Mask" "F.Paste")
			(net "AGND_CURRENT_MON")
			(options
				(clearance outline)
				(anchor circle)
			)
			(primitives
				(gr_poly
					(pts
						(arc
							(start -0.1778 -0.2794)
							(mid -0.249642 -0.249642)
							(end -0.2794 -0.1778)
						)
						(arc
							(start -0.2794 0.1778)
							(mid -0.249642 0.249642)
							(end -0.1778 0.2794)
						)
						(arc
							(start 0.1778 0.2794)
							(mid 0.249642 0.249642)
							(end 0.2794 0.1778)
						)
						(arc
							(start 0.2794 -0.1778)
							(mid 0.249642 -0.249642)
							(end 0.1778 -0.2794)
						)
					)
					(width 0)
					(fill yes)
				)
			)
		)
	)
	(footprint ""
		(layer "F.Cu")
		(at 214.117936 -94.683326 180)
		(property "Reference" "C644"
			(at 0 0 180)
			(layer "F.SilkS")
			(hide yes)
			(effects
				(font
					(size 1.27 1.27)
				)
			)
		)
		(property "Value" "SC470P50V2KX-3GP"
			(at 1.1811 -2.7051 180)
			(unlocked yes)
			(layer "F.Fab")
			(hide yes)
			(effects
				(font
					(size 1.016 1.016)
					(thickness 0.1524)
				)
			)
		)
		(property "Device Type" "C402H22"
			(at 1.1811 -4.2291 180)
			(unlocked yes)
			(layer "F.Fab")
			(hide yes)
			(effects
				(font
					(size 1.016 1.016)
					(thickness 0.1524)
				)
			)
		)
		(duplicate_pad_numbers_are_jumpers no)
		(fp_rect
			(start -0.4318 0.9525)
			(end 0.4318 -0.9525)
			(stroke
				(width 0)
				(type default)
			)
			(fill no)
			(layer "F.CrtYd")
		)
		(fp_rect
			(start -0.4318 0.9525)
			(end 0.4318 -0.9525)
			(stroke
				(width 0)
				(type default)
			)
			(fill no)
			(layer "F.Fab")
		)
		(pad "1" smd custom
			(at 0 -0.4445 180)
			(size 0.1524 0.1524)
			(layers "F.Cu" "F.Mask" "F.Paste")
			(net "P3V3_M2_LL_R")
			(options
				(clearance outline)
				(anchor circle)
			)
			(primitives
				(gr_poly
					(pts
						(arc
							(start 0.3048 -0.2032)
							(mid 0.275042 -0.275042)
							(end 0.2032 -0.3048)
						)
						(arc
							(start -0.2032 -0.3048)
							(mid -0.275042 -0.275042)
							(end -0.3048 -0.2032)
						)
						(arc
							(start -0.3048 0.2032)
							(mid -0.275042 0.275042)
							(end -0.2032 0.3048)
						)
						(arc
							(start 0.2032 0.3048)
							(mid 0.275042 0.275042)
							(end 0.3048 0.2032)
						)
					)
					(width 0)
					(fill yes)
				)
			)
		)
		(pad "2" smd custom
			(at 0 0.4445 180)
			(size 0.1524 0.1524)
			(layers "F.Cu" "F.Mask" "F.Paste")
			(net "P3V3_M2_VFB")
			(options
				(clearance outline)
				(anchor circle)
			)
			(primitives
				(gr_poly
					(pts
						(arc
							(start 0.3048 -0.2032)
							(mid 0.275042 -0.275042)
							(end 0.2032 -0.3048)
						)
						(arc
							(start -0.2032 -0.3048)
							(mid -0.275042 -0.275042)
							(end -0.3048 -0.2032)
						)
						(arc
							(start -0.3048 0.2032)
							(mid -0.275042 0.275042)
							(end -0.2032 0.3048)
						)
						(arc
							(start 0.2032 0.3048)
							(mid 0.275042 0.275042)
							(end 0.3048 0.2032)
						)
					)
					(width 0)
					(fill yes)
				)
			)
		)
	)
	(footprint ""
		(layer "F.Cu")
		(at 26.416 -122.047)
		(property "Reference" "R85"
			(at 0 0 0)
			(layer "F.SilkS")
			(hide yes)
			(effects
				(font
					(size 1.27 1.27)
				)
			)
		)
		(property "Value" "100KR2F-L1-GP"
			(at 0.064008 -3.993896 0)
			(unlocked yes)
			(layer "F.Fab")
			(hide yes)
			(effects
				(font
					(size 1.016 1.016)
					(thickness 0.1524)
				)
			)
		)
		(property "Device Type" "R402H16"
			(at 0.064008 -5.517896 0)
			(unlocked yes)
			(layer "F.Fab")
			(hide yes)
			(effects
				(font
					(size 1.016 1.016)
					(thickness 0.1524)
				)
			)
		)
		(duplicate_pad_numbers_are_jumpers no)
		(fp_line
			(start -0.508 -0.9398)
			(end -0.508 0.9398)
			(stroke
				(width 0.1524)
				(type default)
			)
			(layer "F.SilkS")
		)
		(fp_line
			(start 0.508 -0.9398)
			(end -0.508 -0.9398)
			(stroke
				(width 0.1524)
				(type default)
			)
			(layer "F.SilkS")
		)
		(fp_rect
			(start -0.508 0.9398)
			(end 0.508 -0.9398)
			(stroke
				(width 0)
				(type default)
			)
			(fill no)
			(layer "F.CrtYd")
		)
		(fp_rect
			(start -0.508 0.9398)
			(end 0.508 -0.9398)
			(stroke
				(width 0)
				(type default)
			)
			(fill no)
			(layer "F.Fab")
		)
		(pad "1" smd custom
			(at 0 -0.4445)
			(size 0.1397 0.1397)
			(layers "F.Cu" "F.Mask" "F.Paste")
			(net "WP_ENABLE")
			(options
				(clearance outline)
				(anchor circle)
			)
			(primitives
				(gr_poly
					(pts
						(arc
							(start -0.1778 -0.2794)
							(mid -0.249642 -0.249642)
							(end -0.2794 -0.1778)
						)
						(arc
							(start -0.2794 0.1778)
							(mid -0.249642 0.249642)
							(end -0.1778 0.2794)
						)
						(arc
							(start 0.1778 0.2794)
							(mid 0.249642 0.249642)
							(end 0.2794 0.1778)
						)
						(arc
							(start 0.2794 -0.1778)
							(mid 0.249642 -0.249642)
							(end 0.1778 -0.2794)
						)
					)
					(width 0)
					(fill yes)
				)
			)
		)
		(pad "2" smd custom
			(at 0 0.4445)
			(size 0.1397 0.1397)
			(layers "F.Cu" "F.Mask" "F.Paste")
			(net "GND")
			(options
				(clearance outline)
				(anchor circle)
			)
			(primitives
				(gr_poly
					(pts
						(arc
							(start -0.1778 -0.2794)
							(mid -0.249642 -0.249642)
							(end -0.2794 -0.1778)
						)
						(arc
							(start -0.2794 0.1778)
							(mid -0.249642 0.249642)
							(end -0.1778 0.2794)
						)
						(arc
							(start 0.1778 0.2794)
							(mid 0.249642 0.249642)
							(end 0.2794 0.1778)
						)
						(arc
							(start 0.2794 -0.1778)
							(mid 0.249642 -0.249642)
							(end 0.1778 -0.2794)
						)
					)
					(width 0)
					(fill yes)
				)
			)
		)
	)
)
